(kicad_pcb
	(version 20260206)
	(generator "pcbnew")
	(generator_version "10.0")
	(general
		(thickness 1.6)
		(legacy_teardrops no)
	)
	(paper "A4")
	(title_block
		(title "Bryce Canyon_F.DPB_16315-1-OCP.brd")
		(comment 1 "Bryce Canyon / footprints 746-748 of 2223")
	)
	(layers
		(0 "F.Cu" signal "TOP")
		(4 "In1.Cu" signal "L2GND")
		(6 "In2.Cu" signal "L3")
		(8 "In3.Cu" signal "L4GND")
		(10 "In4.Cu" signal "L5")
		(12 "In5.Cu" signal "L6VCC")
		(14 "In6.Cu" signal "L7VCC")
		(16 "In7.Cu" signal "L8")
		(18 "In8.Cu" signal "L9GND")
		(20 "In9.Cu" signal "L10")
		(22 "In10.Cu" signal "L11GND")
		(2 "B.Cu" signal "BOTTOM")
		(9 "F.Adhes" user "F.Adhesive")
		(11 "B.Adhes" user "B.Adhesive")
		(13 "F.Paste" user "Package Geometry/Pastemask Top")
		(15 "B.Paste" user "Package Geometry/Pastemask Bottom")
		(5 "F.SilkS" user "Ref Des/Silkscreen Top")
		(7 "B.SilkS" user "Ref Des/Silkscreen Bottom")
		(1 "F.Mask" user "Board Geometry/Soldermask Top")
		(3 "B.Mask" user "Board Geometry/Soldermask Bottom")
		(17 "Dwgs.User" user "User.Drawings")
		(19 "Cmts.User" user "User.Comments")
		(21 "Eco1.User" user "User.Eco1")
		(23 "Eco2.User" user "User.Eco2")
		(25 "Edge.Cuts" user "Board Geometry/Outline")
		(27 "Margin" user)
		(31 "F.CrtYd" user "Package Geometry/Place Bound Top")
		(29 "B.CrtYd" user "Package Geometry/Place Bound Bottom")
		(35 "F.Fab" user "Ref Des/Assembly Top")
		(33 "B.Fab" user "Ref Des/Assembly Bottom")
	)
	(footprint ""
		(layer "F.Cu")
		(at 46.283118 -127.78867 180)
		(property "Reference" "Q240"
			(at 0 0 180)
			(layer "F.SilkS")
			(hide yes)
			(effects
				(font
					(size 1.27 1.27)
				)
			)
		)
		(property "Value" "2N7002K-2-GP"
			(at 0.127 -8.9662 180)
			(unlocked yes)
			(layer "F.Fab")
			(hide yes)
			(effects
				(font
					(size 1.016 1.016)
					(thickness 0.1524)
				)
			)
		)
		(property "Device Type" "SOT23DGS2D4H44"
			(at 0.127 -10.4902 180)
			(unlocked yes)
			(layer "F.Fab")
			(hide yes)
			(effects
				(font
					(size 1.016 1.016)
					(thickness 0.1524)
				)
			)
		)
		(duplicate_pad_numbers_are_jumpers no)
		(fp_line
			(start 1.651 1.778)
			(end 1.651 -1.778)
			(stroke
				(width 0.1524)
				(type default)
			)
			(layer "F.SilkS")
		)
		(fp_line
			(start 1.651 -1.778)
			(end -1.651 -1.778)
			(stroke
				(width 0.1524)
				(type default)
			)
			(layer "F.SilkS")
		)
		(fp_line
			(start -1.651 1.778)
			(end 1.651 1.778)
			(stroke
				(width 0.1524)
				(type default)
			)
			(layer "F.SilkS")
		)
		(fp_line
			(start -1.651 -1.778)
			(end -1.651 1.778)
			(stroke
				(width 0.1524)
				(type default)
			)
			(layer "F.SilkS")
		)
		(fp_poly
			(pts
				(xy -1.778 1.8796) (xy -1.778 -1.8796) (xy 1.778 -1.8796) (xy 1.778 1.8796)
			)
			(stroke
				(width 0)
				(type default)
			)
			(fill no)
			(layer "F.CrtYd")
		)
		(fp_poly
			(pts
				(xy -1.778 1.8796) (xy -1.778 -1.8796) (xy 1.778 -1.8796) (xy 1.778 1.8796)
			)
			(stroke
				(width 0)
				(type default)
			)
			(fill no)
			(layer "F.Fab")
		)
		(pad "D" smd custom
			(at 0 -0.9525 180)
			(size 0.1905 0.1905)
			(layers "F.Cu" "F.Mask" "F.Paste")
			(net "FLT_HDD13_N")
			(options
				(clearance outline)
				(anchor circle)
			)
			(primitives
				(gr_poly
					(pts
						(arc
							(start -0.1778 0.5715)
							(mid -0.321484 0.511984)
							(end -0.381 0.3683)
						)
						(arc
							(start -0.381 -0.3683)
							(mid -0.321484 -0.511984)
							(end -0.1778 -0.5715)
						)
						(arc
							(start 0.1778 -0.5715)
							(mid 0.321484 -0.511984)
							(end 0.381 -0.3683)
						)
						(arc
							(start 0.381 0.3683)
							(mid 0.321484 0.511984)
							(end 0.1778 0.5715)
						)
					)
					(width 0)
					(fill yes)
				)
			)
		)
		(pad "G" smd custom
			(at -0.98425 0.9525 180)
			(size 0.1905 0.1905)
			(layers "F.Cu" "F.Mask" "F.Paste")
			(net "DRIVE_A_13_FLT_LED")
			(options
				(clearance outline)
				(anchor circle)
			)
			(primitives
				(gr_poly
					(pts
						(arc
							(start -0.1778 0.5715)
							(mid -0.321484 0.511984)
							(end -0.381 0.3683)
						)
						(arc
							(start -0.381 -0.3683)
							(mid -0.321484 -0.511984)
							(end -0.1778 -0.5715)
						)
						(arc
							(start 0.1778 -0.5715)
							(mid 0.321484 -0.511984)
							(end 0.381 -0.3683)
						)
						(arc
							(start 0.381 0.3683)
							(mid 0.321484 0.511984)
							(end 0.1778 0.5715)
						)
					)
					(width 0)
					(fill yes)
				)
			)
		)
		(pad "S" smd custom
			(at 0.98425 0.9525 180)
			(size 0.1905 0.1905)
			(layers "F.Cu" "F.Mask" "F.Paste")
			(net "GND")
			(options
				(clearance outline)
				(anchor circle)
			)
			(primitives
				(gr_poly
					(pts
						(arc
							(start -0.1778 0.5715)
							(mid -0.321484 0.511984)
							(end -0.381 0.3683)
						)
						(arc
							(start -0.381 -0.3683)
							(mid -0.321484 -0.511984)
							(end -0.1778 -0.5715)
						)
						(arc
							(start 0.1778 -0.5715)
							(mid 0.321484 -0.511984)
							(end 0.381 -0.3683)
						)
						(arc
							(start 0.381 0.3683)
							(mid 0.321484 0.511984)
							(end 0.1778 0.5715)
						)
					)
					(width 0)
					(fill yes)
				)
			)
		)
	)
	(footprint ""
		(layer "F.Cu")
		(at 64.013334 -43.660568 90)
		(property "Reference" "C364"
			(at 0 0 90)
			(layer "F.SilkS")
			(hide yes)
			(effects
				(font
					(size 1.27 1.27)
				)
			)
		)
		(property "Value" "SCD01U16V1KX-GP"
			(at -2.8321 -1.7399 90)
			(unlocked yes)
			(layer "F.Fab")
			(hide yes)
			(effects
				(font
					(size 1.016 1.016)
					(thickness 0.1524)
				)
			)
		)
		(property "Device Type" "C0201H13"
			(at -2.8321 -3.2639 90)
			(unlocked yes)
			(layer "F.Fab")
			(hide yes)
			(effects
				(font
					(size 1.016 1.016)
					(thickness 0.1524)
				)
			)
		)
		(duplicate_pad_numbers_are_jumpers no)
		(fp_rect
			(start -0.2794 0.6477)
			(end 0.2794 -0.6477)
			(stroke
				(width 0)
				(type default)
			)
			(fill no)
			(layer "F.CrtYd")
		)
		(fp_rect
			(start -0.2794 0.6477)
			(end 0.2794 -0.6477)
			(stroke
				(width 0)
				(type default)
			)
			(fill no)
			(layer "F.Fab")
		)
		(pad "1" smd custom
			(at 0 -0.2794 90)
			(size 0.0762 0.0762)
			(layers "F.Cu" "F.Mask" "F.Paste")
			(net "SAS_HDD_RX_P25")
			(options
				(clearance outline)
				(anchor circle)
			)
			(primitives
				(gr_poly
					(pts
						(arc
							(start 0.1524 -0.127)
							(mid 0.137521 -0.162921)
							(end 0.1016 -0.1778)
						)
						(arc
							(start -0.1016 -0.1778)
							(mid -0.137521 -0.162921)
							(end -0.1524 -0.127)
						)
						(arc
							(start -0.1524 0.127)
							(mid -0.137521 0.162921)
							(end -0.1016 0.1778)
						)
						(arc
							(start 0.1016 0.1778)
							(mid 0.137521 0.162921)
							(end 0.1524 0.127)
						)
					)
					(width 0)
					(fill yes)
				)
			)
		)
		(pad "2" smd custom
			(at 0 0.2794 90)
			(size 0.0762 0.0762)
			(layers "F.Cu" "F.Mask" "F.Paste")
			(net "PHY_SCC_A_TO_DRV_A_25_DP")
			(options
				(clearance outline)
				(anchor circle)
			)
			(primitives
				(gr_poly
					(pts
						(arc
							(start 0.1524 -0.127)
							(mid 0.137521 -0.162921)
							(end 0.1016 -0.1778)
						)
						(arc
							(start -0.1016 -0.1778)
							(mid -0.137521 -0.162921)
							(end -0.1524 -0.127)
						)
						(arc
							(start -0.1524 0.127)
							(mid -0.137521 0.162921)
							(end -0.1016 0.1778)
						)
						(arc
							(start 0.1016 0.1778)
							(mid 0.137521 0.162921)
							(end 0.1524 0.127)
						)
					)
					(width 0)
					(fill yes)
				)
			)
		)
	)
	(footprint ""
		(layer "F.Cu")
		(at 388.649972 -172.909992 -90)
		(property "Reference" "HDDSAS20"
			(at 0 0 270)
			(layer "F.SilkS")
			(hide yes)
			(effects
				(font
					(size 1.27 1.27)
				)
			)
		)
		(property "Value" "SKT-SAS15P-14P-45-GP"
			(at -20.7645 -8.9789 270)
			(unlocked yes)
			(layer "F.Fab")
			(hide yes)
			(effects
				(font
					(size 1.016 1.016)
					(thickness 0.1524)
				)
			)
		)
		(property "Device Type" "10120818-001C-TRLF"
			(at -20.7645 -10.5029 270)
			(unlocked yes)
			(layer "F.Fab")
			(hide yes)
			(effects
				(font
					(size 1.016 1.016)
					(thickness 0.1524)
				)
			)
		)
		(duplicate_pad_numbers_are_jumpers no)
		(fp_line
			(start 1.651 4.2926)
			(end 1.651 3.0099)
			(stroke
				(width 0.1524)
				(type default)
			)
			(layer "F.SilkS")
		)
		(fp_line
			(start 8.509 4.2926)
			(end 1.651 4.2926)
			(stroke
				(width 0.1524)
				(type default)
			)
			(layer "F.SilkS")
		)
		(fp_line
			(start -23.4188 3.0099)
			(end -23.4188 -3.2512)
			(stroke
				(width 0.1524)
				(type default)
			)
			(layer "F.SilkS")
		)
		(fp_line
			(start 1.651 3.0099)
			(end -23.4188 3.0099)
			(stroke
				(width 0.1524)
				(type default)
			)
			(layer "F.SilkS")
		)
		(fp_line
			(start 8.509 3.0099)
			(end 8.509 4.2926)
			(stroke
				(width 0.1524)
				(type default)
			)
			(layer "F.SilkS")
		)
		(fp_line
			(start 23.4188 3.0099)
			(end 8.509 3.0099)
			(stroke
				(width 0.1524)
				(type default)
			)
			(layer "F.SilkS")
		)
		(fp_line
			(start -23.4188 -3.2512)
			(end 23.4188 -3.2512)
			(stroke
				(width 0.1524)
				(type default)
			)
			(layer "F.SilkS")
		)
		(fp_line
			(start 23.4188 -3.2512)
			(end 23.4188 3.0099)
			(stroke
				(width 0.1524)
				(type default)
			)
			(layer "F.SilkS")
		)
		(fp_line
			(start 15.5067 -3.3401)
			(end 16.2687 -3.3401)
			(stroke
				(width 0.3302)
				(type default)
			)
			(layer "F.SilkS")
		)
		(fp_poly
			(pts
				(xy 15.868904 -3.230372) (xy 16.503904 -3.865372) (xy 15.233904 -3.865372)
			)
			(stroke
				(width 0)
				(type default)
			)
			(fill yes)
			(layer "F.SilkS")
		)
		(fp_poly
			(pts
				(xy -22.8727 -2.7559) (xy 22.8727 -2.7559) (xy 22.8727 2.7559) (xy 8.255 2.7559) (xy 8.255 3.5179)
				(xy 1.905 3.5179) (xy 1.905 2.7559) (xy -22.8727 2.7559)
			)
			(stroke
				(width 0)
				(type default)
			)
			(fill no)
			(layer "F.CrtYd")
		)
		(fp_poly
			(pts
				(xy 1.397 4.5466) (xy 1.397 3.2639) (xy -23.6728 3.2639) (xy -23.6728 -3.5052) (xy 23.6728 -3.5052)
				(xy 23.6728 -0.00635) (xy 22.8727 -0.00635) (xy 22.8727 -2.7559) (xy -22.8727 -2.7559) (xy -22.8727 2.7559)
				(xy 1.905 2.7559) (xy 1.905 3.5179) (xy 8.255 3.5179) (xy 8.255 2.7559) (xy 22.8727 2.7559) (xy 22.8727 0.00635)
				(xy 23.6728 0.00635) (xy 23.6728 3.2639) (xy 8.763 3.2639) (xy 8.763 4.5466)
			)
			(stroke
				(width 0)
				(type default)
			)
			(fill no)
			(layer "F.CrtYd")
		)
		(fp_poly
			(pts
				(xy 1.397 4.5466) (xy 1.397 3.2639) (xy -23.6728 3.2639) (xy -23.6728 -3.5052) (xy 23.6728 -3.5052)
				(xy 23.6728 3.2639) (xy 8.763 3.2639) (xy 8.763 4.5466)
			)
			(stroke
				(width 0)
				(type default)
			)
			(fill no)
			(layer "F.Fab")
		)
		(pad "" np_thru_hole circle
			(at -18.874994 0 270)
			(size 0.254 0.254)
			(drill 1.3462)
			(layers "*.Cu" "*.Mask")
			(clearance 0.9017)
			(thermal_gap 0.9017)
		)
		(pad "" np_thru_hole circle
			(at 18.874994 0 270)
			(size 0.254 0.254)
			(drill 0.9398)
			(layers "*.Cu" "*.Mask")
			(clearance 0.6985)
			(thermal_gap 0.6985)
		)
		(pad "G1" smd rect
			(at 21.874988 0 270)
			(size 2.5908 2.5908)
			(layers "F.Cu" "F.Mask" "F.Paste")
			(net "GND")
		)
		(pad "G2" smd rect
			(at -21.874988 0 270)
			(size 2.5908 2.5908)
			(layers "F.Cu" "F.Mask" "F.Paste")
			(net "GND")
		)
		(pad "P1" smd rect
			(at 1.905 -1.82499 270)
			(size 0.6096 2.3622)
			(layers "F.Cu" "F.Mask" "F.Paste")
			(net "Net_2111")
		)
		(pad "P2" smd rect
			(at 0.635 -1.82499 270)
			(size 0.6096 2.3622)
			(layers "F.Cu" "F.Mask" "F.Paste")
			(net "Net_2112")
		)
		(pad "P3" smd rect
			(at -0.635 -1.82499 270)
			(size 0.6096 2.3622)
			(layers "F.Cu" "F.Mask" "F.Paste")
			(net "Net_2113")
		)
		(pad "P4" smd rect
			(at -1.905 -1.82499 270)
			(size 0.6096 2.3622)
			(layers "F.Cu" "F.Mask" "F.Paste")
			(net "GND")
		)
		(pad "P5" smd rect
			(at -3.175 -1.82499 270)
			(size 0.6096 2.3622)
			(layers "F.Cu" "F.Mask" "F.Paste")
			(net "HDD_PRSNT_20")
		)
		(pad "P6" smd rect
			(at -4.445 -1.82499 270)
			(size 0.6096 2.3622)
			(layers "F.Cu" "F.Mask" "F.Paste")
			(net "GND")
		)
		(pad "P7" smd rect
			(at -5.715 -1.82499 270)
			(size 0.6096 2.3622)
			(layers "F.Cu" "F.Mask" "F.Paste")
			(net "5V_PRE_20")
		)
		(pad "P8" smd rect
			(at -6.985 -1.82499 270)
			(size 0.6096 2.3622)
			(layers "F.Cu" "F.Mask" "F.Paste")
			(net "P5V_HDD20")
		)
		(pad "P9" smd rect
			(at -8.255 -1.82499 270)
			(size 0.6096 2.3622)
			(layers "F.Cu" "F.Mask" "F.Paste")
			(net "P5V_HDD20")
		)
		(pad "P10" smd rect
			(at -9.525 -1.82499 270)
			(size 0.6096 2.3622)
			(layers "F.Cu" "F.Mask" "F.Paste")
			(net "GND")
		)
		(pad "P11" smd rect
			(at -10.795 -1.82499 270)
			(size 0.6096 2.3622)
			(layers "F.Cu" "F.Mask" "F.Paste")
			(net "ACT_HDD_20")
		)
		(pad "P12" smd rect
			(at -12.065 -1.82499 270)
			(size 0.6096 2.3622)
			(layers "F.Cu" "F.Mask" "F.Paste")
			(net "GND")
		)
		(pad "P13" smd rect
			(at -13.335 -1.82499 270)
			(size 0.6096 2.3622)
			(layers "F.Cu" "F.Mask" "F.Paste")
			(net "12V_PRE_20")
		)
		(pad "P14" smd rect
			(at -14.605 -1.82499 270)
			(size 0.6096 2.3622)
			(layers "F.Cu" "F.Mask" "F.Paste")
			(net "P12V_HDD20")
		)
		(pad "P15" smd rect
			(at -15.875 -1.82499 270)
			(size 0.6096 2.3622)
			(layers "F.Cu" "F.Mask" "F.Paste")
			(net "P12V_HDD20")
		)
		(pad "S1" smd rect
			(at 15.875 -1.82499 270)
			(size 0.6096 2.3622)
			(layers "F.Cu" "F.Mask" "F.Paste")
			(net "GND")
		)
		(pad "S2" smd rect
			(at 14.605 -1.82499 270)
			(size 0.6096 2.3622)
			(layers "F.Cu" "F.Mask" "F.Paste")
			(net "SAS_HDD_RX_P20")
		)
		(pad "S3" smd rect
			(at 13.335 -1.82499 270)
			(size 0.6096 2.3622)
			(layers "F.Cu" "F.Mask" "F.Paste")
			(net "SAS_HDD_RX_N20")
		)
		(pad "S4" smd rect
			(at 12.065 -1.82499 270)
			(size 0.6096 2.3622)
			(layers "F.Cu" "F.Mask" "F.Paste")
			(net "GND")
		)
		(pad "S5" smd rect
			(at 10.795 -1.82499 270)
			(size 0.6096 2.3622)
			(layers "F.Cu" "F.Mask" "F.Paste")
			(net "PHY_DRV_A_TO_SCC_A_20_DN")
		)
		(pad "S6" smd rect
			(at 9.525 -1.82499 270)
			(size 0.6096 2.3622)
			(layers "F.Cu" "F.Mask" "F.Paste")
			(net "PHY_DRV_A_TO_SCC_A_20_DP")
		)
		(pad "S7" smd rect
			(at 8.255 -1.82499 270)
			(size 0.6096 2.3622)
			(layers "F.Cu" "F.Mask" "F.Paste")
			(net "GND")
		)
		(pad "S8" smd rect
			(at 7.480046 2.845054 270)
			(size 0.508 2.3622)
			(layers "F.Cu" "F.Mask" "F.Paste")
			(net "GND")
		)
		(pad "S9" smd rect
			(at 6.679946 2.845054 270)
			(size 0.508 2.3622)
			(layers "F.Cu" "F.Mask" "F.Paste")
			(net "Net_458")
		)
		(pad "S10" smd rect
			(at 5.8801 2.845054 270)
			(size 0.508 2.3622)
			(layers "F.Cu" "F.Mask" "F.Paste")
			(net "Net_350")
		)
		(pad "S11" smd rect
			(at 5.08 2.845054 270)
			(size 0.508 2.3622)
			(layers "F.Cu" "F.Mask" "F.Paste")
			(net "GND")
		)
		(pad "S12" smd rect
			(at 4.2799 2.845054 270)
			(size 0.508 2.3622)
			(layers "F.Cu" "F.Mask" "F.Paste")
			(net "Net_386")
		)
		(pad "S13" smd rect
			(at 3.480054 2.845054 270)
			(size 0.508 2.3622)
			(layers "F.Cu" "F.Mask" "F.Paste")
			(net "Net_422")
		)
		(pad "S14" smd rect
			(at 2.679954 2.845054 270)
			(size 0.508 2.3622)
			(layers "F.Cu" "F.Mask" "F.Paste")
			(net "GND")
		)
		(zone
			(layer "F.Cu")
			(hatch none 0.5)
			(connect_pads
				(clearance 0)
			)
			(min_thickness 0.25)
			(keepout
				(tracks allowed)
				(vias not_allowed)
				(pads allowed)
				(copperpour not_allowed)
				(footprints allowed)
			)
			(placement
				(enabled no)
				(sheetname "")
			)
			(fill
				(thermal_gap 0.5)
				(thermal_bridge_width 0.5)
				(island_removal_mode 0)
			)
			(polygon
				(pts
					(xy 392.307572 -189.648592) (xy 385.233672 -189.648592) (xy 385.233672 -196.582792) (xy 386.338572 -196.582792)
					(xy 386.338572 -192.467992) (xy 390.961372 -192.467992) (xy 390.961372 -196.582792) (xy 392.307572 -196.582792)
				)
			)
		)
		(zone
			(layer "F.Cu")
			(hatch none 0.5)
			(connect_pads
				(clearance 0)
			)
			(min_thickness 0.25)
			(keepout
				(tracks not_allowed)
				(vias allowed)
				(pads allowed)
				(copperpour not_allowed)
				(footprints allowed)
			)
			(placement
				(enabled no)
				(sheetname "")
			)
			(fill
				(thermal_gap 0.5)
				(thermal_bridge_width 0.5)
				(island_removal_mode 0)
			)
			(polygon
				(pts
					(xy 392.307572 -189.648592) (xy 385.233672 -189.648592) (xy 385.233672 -196.582792) (xy 386.338572 -196.582792)
					(xy 386.338572 -192.467992) (xy 390.961372 -192.467992) (xy 390.961372 -196.582792) (xy 392.307572 -196.582792)
				)
			)
		)
		(zone
			(layer "F.Cu")
			(hatch none 0.5)
			(connect_pads
				(clearance 0)
			)
			(min_thickness 0.25)
			(keepout
				(tracks allowed)
				(vias not_allowed)
				(pads allowed)
				(copperpour not_allowed)
				(footprints allowed)
			)
			(placement
				(enabled no)
				(sheetname "")
			)
			(fill
				(thermal_gap 0.5)
				(thermal_bridge_width 0.5)
				(island_removal_mode 0)
			)
			(polygon
				(pts
					(xy 392.307572 -156.171392) (xy 385.233672 -156.171392) (xy 385.233672 -149.237192) (xy 386.338572 -149.237192)
					(xy 386.338572 -153.351992) (xy 390.961372 -153.351992) (xy 390.961372 -149.237192) (xy 392.307572 -149.237192)
				)
			)
		)
		(zone
			(layer "F.Cu")
			(hatch none 0.5)
			(connect_pads
				(clearance 0)
			)
			(min_thickness 0.25)
			(keepout
				(tracks not_allowed)
				(vias allowed)
				(pads allowed)
				(copperpour not_allowed)
				(footprints allowed)
			)
			(placement
				(enabled no)
				(sheetname "")
			)
			(fill
				(thermal_gap 0.5)
				(thermal_bridge_width 0.5)
				(island_removal_mode 0)
			)
			(polygon
				(pts
					(xy 392.307572 -156.171392) (xy 385.233672 -156.171392) (xy 385.233672 -149.237192) (xy 386.338572 -149.237192)
					(xy 386.338572 -153.351992) (xy 390.961372 -153.351992) (xy 390.961372 -149.237192) (xy 392.307572 -149.237192)
				)
			)
		)
		(zone
			(layers "F.Cu" "B.Cu" "In1.Cu" "In2.Cu" "In3.Cu" "In4.Cu" "In5.Cu" "In6.Cu"
				"In7.Cu" "In8.Cu" "In9.Cu" "In10.Cu"
			)
			(hatch none 0.5)
			(connect_pads
				(clearance 0)
			)
			(min_thickness 0.25)
			(keepout
				(tracks not_allowed)
				(vias allowed)
				(pads allowed)
				(copperpour not_allowed)
				(footprints allowed)
			)
			(placement
				(enabled no)
				(sheetname "")
			)
			(fill
				(thermal_gap 0.5)
				(thermal_bridge_width 0.5)
				(island_removal_mode 0)
			)
			(polygon
				(pts
					(arc
						(start 389.424672 -154.034998)
						(mid 387.875272 -154.034998)
						(end 389.424672 -154.034998)
					)
				)
			)
		)
		(zone
			(layers "F.Cu" "B.Cu" "In1.Cu" "In2.Cu" "In3.Cu" "In4.Cu" "In5.Cu" "In6.Cu"
				"In7.Cu" "In8.Cu" "In9.Cu" "In10.Cu"
			)
			(hatch none 0.5)
			(connect_pads
				(clearance 0)
			)
			(min_thickness 0.25)
			(keepout
				(tracks not_allowed)
				(vias allowed)
				(pads allowed)
				(copperpour not_allowed)
				(footprints allowed)
			)
			(placement
				(enabled no)
				(sheetname "")
			)
			(fill
				(thermal_gap 0.5)
				(thermal_bridge_width 0.5)
				(island_removal_mode 0)
			)
			(polygon
				(pts
					(arc
						(start 389.627872 -191.784986)
						(mid 387.672072 -191.784986)
						(end 389.627872 -191.784986)
					)
				)
			)
		)
	)
)
